# T6G (Grand Teton) — schematic netlist excerpt (pin names and nets, part order shuffled) for the footprints in the layout excerpt that follows; sources: Cadence DE-HDL packaged netlist, KiCad conversion of 04192023_DAF0TMB3IC0_F0TG_MB_C_brd_V02_OCP.brd

R7  Q_RES  10K 1% CHIP  pkg 0402LF  page 86 : A = PD_CHA_CPU0_DIMM0_SAA ; B = GND
R381  Q_RES  15 1% CHIP  pkg 0402LF  page 16 : A = M_G_CPU0_ALERT_N ; B = M_G_CPU0_ALERT_R_N
R826  Q_RES  1K 1% CHIP  pkg 0201LF  page 185 : A = P1V8_CPU1_RT_1D ; B = SMB_RT_CPU1_P2_ROM_R_SDA

(kicad_pcb
	(version 20260206)
	(generator "pcbnew")
	(generator_version "10.0")
	(general
		(thickness 1.6)
		(legacy_teardrops no)
	)
	(paper "A4")
	(title_block
		(title "04192023_DAF0TMB3IC0_F0TG_MB_C_brd_V02_OCP.brd")
		(comment 1 "Grand Teton / footprints 6123-6125 of 8354")
	)
	(layers
		(0 "F.Cu" signal "TOP")
		(4 "In1.Cu" signal "GND")
		(6 "In2.Cu" signal "IN1")
		(8 "In3.Cu" signal "GND1")
		(10 "In4.Cu" signal "IN2")
		(12 "In5.Cu" signal "GND2")
		(14 "In6.Cu" signal "IN3")
		(16 "In7.Cu" signal "GND3")
		(18 "In8.Cu" signal "VCC")
		(20 "In9.Cu" signal "VCC1")
		(22 "In10.Cu" signal "GND4")
		(24 "In11.Cu" signal "IN4")
		(26 "In12.Cu" signal "GND5")
		(28 "In13.Cu" signal "IN5")
		(30 "In14.Cu" signal "GND6")
		(32 "In15.Cu" signal "IN6")
		(34 "In16.Cu" signal "GND7")
		(2 "B.Cu" signal "BOTTOM")
		(9 "F.Adhes" user "F.Adhesive")
		(11 "B.Adhes" user "B.Adhesive")
		(13 "F.Paste" user "Package Geometry/Pastemask Top")
		(15 "B.Paste" user "Package Geometry/Pastemask Bottom")
		(5 "F.SilkS" user "Ref Des/Silkscreen Top")
		(7 "B.SilkS" user "Ref Des/Silkscreen Bottom")
		(1 "F.Mask" user "Board Geometry/Soldermask Top")
		(3 "B.Mask" user "Board Geometry/Soldermask Bottom")
		(17 "Dwgs.User" user "User.Drawings")
		(19 "Cmts.User" user "User.Comments")
		(21 "Eco1.User" user "User.Eco1")
		(23 "Eco2.User" user "User.Eco2")
		(25 "Edge.Cuts" user "Board Geometry/Outline")
		(27 "Margin" user)
		(31 "F.CrtYd" user "Package Geometry/Place Bound Top")
		(29 "B.CrtYd" user "Package Geometry/Place Bound Bottom")
		(35 "F.Fab" user "Ref Des/Assembly Top")
		(33 "B.Fab" user "Ref Des/Assembly Bottom")
	)
	(footprint ""
		(layer "B.Cu")
		(at 415.471102 -244.08511)
		(property "Reference" "R381"
			(at 0 0 0)
			(layer "B.SilkS")
			(hide yes)
			(effects
				(font
					(size 1.27 1.27)
				)
				(justify mirror)
			)
		)
		(property "Value" ""
			(at 0 0 0)
			(layer "B.Fab")
			(effects
				(font
					(size 1.27 1.27)
				)
				(justify mirror)
			)
		)
		(duplicate_pad_numbers_are_jumpers no)
		(fp_line
			(start -0.7874 -0.4064)
			(end -0.7874 0.4064)
			(stroke
				(width 0.1524)
				(type default)
			)
			(layer "B.SilkS")
		)
		(fp_line
			(start -0.7874 0.4064)
			(end 0.7874 0.4064)
			(stroke
				(width 0.1524)
				(type default)
			)
			(layer "B.SilkS")
		)
		(fp_line
			(start 0.7874 -0.4064)
			(end -0.7874 -0.4064)
			(stroke
				(width 0.1524)
				(type default)
			)
			(layer "B.SilkS")
		)
		(fp_line
			(start 0.7874 0.4064)
			(end 0.7874 -0.4064)
			(stroke
				(width 0.1524)
				(type default)
			)
			(layer "B.SilkS")
		)
		(fp_line
			(start -0.67945 -0.3048)
			(end -0.67945 0.3048)
			(stroke
				(width 0.1)
				(type default)
			)
			(layer "B.Fab")
		)
		(fp_line
			(start -0.67945 0.3048)
			(end -0.120396 0.3048)
			(stroke
				(width 0.1)
				(type default)
			)
			(layer "B.Fab")
		)
		(fp_line
			(start -0.12065 -0.3048)
			(end -0.67945 -0.3048)
			(stroke
				(width 0.1)
				(type default)
			)
			(layer "B.Fab")
		)
		(fp_line
			(start -0.12065 -0.2794)
			(end -0.12065 -0.3048)
			(stroke
				(width 0.1)
				(type default)
			)
			(layer "B.Fab")
		)
		(fp_line
			(start -0.120396 0.2794)
			(end 0.12065 0.2794)
			(stroke
				(width 0.1)
				(type default)
			)
			(layer "B.Fab")
		)
		(fp_line
			(start -0.120396 0.3048)
			(end -0.120396 0.2794)
			(stroke
				(width 0.1)
				(type default)
			)
			(layer "B.Fab")
		)
		(fp_line
			(start 0.12065 -0.305054)
			(end 0.12065 -0.2794)
			(stroke
				(width 0.1)
				(type default)
			)
			(layer "B.Fab")
		)
		(fp_line
			(start 0.12065 -0.2794)
			(end -0.12065 -0.2794)
			(stroke
				(width 0.1)
				(type default)
			)
			(layer "B.Fab")
		)
		(fp_line
			(start 0.12065 0.2794)
			(end 0.12065 0.3048)
			(stroke
				(width 0.1)
				(type default)
			)
			(layer "B.Fab")
		)
		(fp_line
			(start 0.12065 0.3048)
			(end 0.67945 0.3048)
			(stroke
				(width 0.1)
				(type default)
			)
			(layer "B.Fab")
		)
		(fp_line
			(start 0.67945 -0.305054)
			(end 0.12065 -0.305054)
			(stroke
				(width 0.1)
				(type default)
			)
			(layer "B.Fab")
		)
		(fp_line
			(start 0.67945 0.3048)
			(end 0.67945 -0.305054)
			(stroke
				(width 0.1)
				(type default)
			)
			(layer "B.Fab")
		)
		(pad "1" smd circle
			(at 0.40005 0 180)
			(size 0 0)
			(layers "B.Cu" "B.Mask" "B.Paste")
			(net "M_G_CPU0_ALERT_N")
		)
		(pad "2" smd circle
			(at -0.40005 0 180)
			(size 0 0)
			(layers "B.Cu" "B.Mask" "B.Paste")
			(net "M_G_CPU0_ALERT_R_N")
		)
	)
	(footprint ""
		(layer "B.Cu")
		(at 164.107368 -420.184834 90)
		(property "Reference" "R826"
			(at 0 0 90)
			(layer "B.SilkS")
			(hide yes)
			(effects
				(font
					(size 1.27 1.27)
				)
				(justify mirror)
			)
		)
		(property "Value" ""
			(at 0 0 90)
			(layer "B.Fab")
			(effects
				(font
					(size 1.27 1.27)
				)
				(justify mirror)
			)
		)
		(duplicate_pad_numbers_are_jumpers no)
		(fp_line
			(start 0.32512 -0.175006)
			(end -0.32512 -0.175006)
			(stroke
				(width 0.1)
				(type default)
			)
			(layer "B.Fab")
		)
		(fp_line
			(start -0.32512 -0.175006)
			(end -0.32512 0.175006)
			(stroke
				(width 0.1)
				(type default)
			)
			(layer "B.Fab")
		)
		(fp_line
			(start 0.32512 0.175006)
			(end 0.32512 -0.175006)
			(stroke
				(width 0.1)
				(type default)
			)
			(layer "B.Fab")
		)
		(fp_line
			(start -0.32512 0.175006)
			(end 0.32512 0.175006)
			(stroke
				(width 0.1)
				(type default)
			)
			(layer "B.Fab")
		)
		(pad "1" smd rect
			(at 0.2667 0 270)
			(size 0.3048 0.381)
			(layers "B.Cu" "B.Mask" "B.Paste")
			(net "P1V8_CPU1_RT_1D")
		)
		(pad "2" smd rect
			(at -0.2667 0 90)
			(size 0.3048 0.381)
			(layers "B.Cu" "B.Mask" "B.Paste")
			(net "SMB_RT_CPU1_P2_ROM_R_SDA")
		)
	)
	(footprint ""
		(layer "B.Cu")
		(at 304.023776 -194.88531 180)
		(property "Reference" "R7"
			(at 0 0 0)
			(layer "B.SilkS")
			(hide yes)
			(effects
				(font
					(size 1.27 1.27)
				)
				(justify mirror)
			)
		)
		(property "Value" ""
			(at 0 0 0)
			(layer "B.Fab")
			(effects
				(font
					(size 1.27 1.27)
				)
				(justify mirror)
			)
		)
		(duplicate_pad_numbers_are_jumpers no)
		(fp_line
			(start 0.7874 0.4064)
			(end 0.7874 -0.4064)
			(stroke
				(width 0.1524)
				(type default)
			)
			(layer "B.SilkS")
		)
		(fp_line
			(start 0.7874 -0.4064)
			(end -0.7874 -0.4064)
			(stroke
				(width 0.1524)
				(type default)
			)
			(layer "B.SilkS")
		)
		(fp_line
			(start -0.7874 0.4064)
			(end 0.7874 0.4064)
			(stroke
				(width 0.1524)
				(type default)
			)
			(layer "B.SilkS")
		)
		(fp_line
			(start -0.7874 -0.4064)
			(end -0.7874 0.4064)
			(stroke
				(width 0.1524)
				(type default)
			)
			(layer "B.SilkS")
		)
		(fp_line
			(start 0.67945 0.3048)
			(end 0.67945 -0.305054)
			(stroke
				(width 0.1)
				(type default)
			)
			(layer "B.Fab")
		)
		(fp_line
			(start 0.67945 -0.305054)
			(end 0.12065 -0.305054)
			(stroke
				(width 0.1)
				(type default)
			)
			(layer "B.Fab")
		)
		(fp_line
			(start 0.12065 0.3048)
			(end 0.67945 0.3048)
			(stroke
				(width 0.1)
				(type default)
			)
			(layer "B.Fab")
		)
		(fp_line
			(start 0.12065 0.2794)
			(end 0.12065 0.3048)
			(stroke
				(width 0.1)
				(type default)
			)
			(layer "B.Fab")
		)
		(fp_line
			(start 0.12065 -0.2794)
			(end -0.12065 -0.2794)
			(stroke
				(width 0.1)
				(type default)
			)
			(layer "B.Fab")
		)
		(fp_line
			(start 0.12065 -0.305054)
			(end 0.12065 -0.2794)
			(stroke
				(width 0.1)
				(type default)
			)
			(layer "B.Fab")
		)
		(fp_line
			(start -0.120396 0.3048)
			(end -0.120396 0.2794)
			(stroke
				(width 0.1)
				(type default)
			)
			(layer "B.Fab")
		)
		(fp_line
			(start -0.120396 0.2794)
			(end 0.12065 0.2794)
			(stroke
				(width 0.1)
				(type default)
			)
			(layer "B.Fab")
		)
		(fp_line
			(start -0.12065 -0.2794)
			(end -0.12065 -0.3048)
			(stroke
				(width 0.1)
				(type default)
			)
			(layer "B.Fab")
		)
		(fp_line
			(start -0.12065 -0.3048)
			(end -0.67945 -0.3048)
			(stroke
				(width 0.1)
				(type default)
			)
			(layer "B.Fab")
		)
		(fp_line
			(start -0.67945 0.3048)
			(end -0.120396 0.3048)
			(stroke
				(width 0.1)
				(type default)
			)
			(layer "B.Fab")
		)
		(fp_line
			(start -0.67945 -0.3048)
			(end -0.67945 0.3048)
			(stroke
				(width 0.1)
				(type default)
			)
			(layer "B.Fab")
		)
		(pad "1" smd circle
			(at 0.40005 0)
			(size 0 0)
			(layers "B.Cu" "B.Mask" "B.Paste")
			(net "PD_CHA_CPU0_DIMM0_SAA")
		)
		(pad "2" smd circle
			(at -0.40005 0)
			(size 0 0)
			(layers "B.Cu" "B.Mask" "B.Paste")
			(net "GND")
		)
	)
)
